# T6G (Grand Teton) — schematic netlist excerpt (pin names and nets, part order shuffled) for the footprints in the layout excerpt that follows; sources: Cadence DE-HDL packaged netlist, KiCad conversion of 04192023_DAF0TMB3IC0_F0TG_MB_C_brd_V02_OCP.brd

R1274  Q_RES  0 5% CHIP  pkg 0402LF  page 357 : A = SMB_INA230_7_3V3AUX_SCL_R ; B = SMB_INA230_7_3V3AUX_SCL_R1
PR290  Q_RES  40.2K 1% CHIP  pkg 0402LF  page 193 : A = P5V_AUX ; B = PVDDCR_CPU0_P0_VMON

(kicad_pcb
	(version 20260206)
	(generator "pcbnew")
	(generator_version "10.0")
	(general
		(thickness 1.6)
		(legacy_teardrops no)
	)
	(paper "A4")
	(title_block
		(title "04192023_DAF0TMB3IC0_F0TG_MB_C_brd_V02_OCP.brd")
		(comment 1 "Grand Teton / footprints 4107-4108 of 8354")
	)
	(layers
		(0 "F.Cu" signal "TOP")
		(4 "In1.Cu" signal "GND")
		(6 "In2.Cu" signal "IN1")
		(8 "In3.Cu" signal "GND1")
		(10 "In4.Cu" signal "IN2")
		(12 "In5.Cu" signal "GND2")
		(14 "In6.Cu" signal "IN3")
		(16 "In7.Cu" signal "GND3")
		(18 "In8.Cu" signal "VCC")
		(20 "In9.Cu" signal "VCC1")
		(22 "In10.Cu" signal "GND4")
		(24 "In11.Cu" signal "IN4")
		(26 "In12.Cu" signal "GND5")
		(28 "In13.Cu" signal "IN5")
		(30 "In14.Cu" signal "GND6")
		(32 "In15.Cu" signal "IN6")
		(34 "In16.Cu" signal "GND7")
		(2 "B.Cu" signal "BOTTOM")
		(9 "F.Adhes" user "F.Adhesive")
		(11 "B.Adhes" user "B.Adhesive")
		(13 "F.Paste" user "Package Geometry/Pastemask Top")
		(15 "B.Paste" user "Package Geometry/Pastemask Bottom")
		(5 "F.SilkS" user "Ref Des/Silkscreen Top")
		(7 "B.SilkS" user "Ref Des/Silkscreen Bottom")
		(1 "F.Mask" user "Board Geometry/Soldermask Top")
		(3 "B.Mask" user "Board Geometry/Soldermask Bottom")
		(17 "Dwgs.User" user "User.Drawings")
		(19 "Cmts.User" user "User.Comments")
		(21 "Eco1.User" user "User.Eco1")
		(23 "Eco2.User" user "User.Eco2")
		(25 "Edge.Cuts" user "Board Geometry/Outline")
		(27 "Margin" user)
		(31 "F.CrtYd" user "Package Geometry/Place Bound Top")
		(29 "B.CrtYd" user "Package Geometry/Place Bound Bottom")
		(35 "F.Fab" user "Ref Des/Assembly Top")
		(33 "B.Fab" user "Ref Des/Assembly Bottom")
	)
	(footprint ""
		(layer "F.Cu")
		(at 384.113278 -140.202158 180)
		(property "Reference" "PR290"
			(at 0 0 180)
			(layer "F.SilkS")
			(hide yes)
			(effects
				(font
					(size 1.27 1.27)
				)
			)
		)
		(property "Value" ""
			(at 0 0 180)
			(layer "F.Fab")
			(effects
				(font
					(size 1.27 1.27)
				)
			)
		)
		(duplicate_pad_numbers_are_jumpers no)
		(fp_line
			(start 0.7874 0.4064)
			(end -0.7874 0.4064)
			(stroke
				(width 0.1524)
				(type default)
			)
			(layer "F.SilkS")
		)
		(fp_line
			(start 0.7874 -0.4064)
			(end 0.7874 0.4064)
			(stroke
				(width 0.1524)
				(type default)
			)
			(layer "F.SilkS")
		)
		(fp_line
			(start -0.7874 0.4064)
			(end -0.7874 -0.4064)
			(stroke
				(width 0.1524)
				(type default)
			)
			(layer "F.SilkS")
		)
		(fp_line
			(start -0.7874 -0.4064)
			(end 0.7874 -0.4064)
			(stroke
				(width 0.1524)
				(type default)
			)
			(layer "F.SilkS")
		)
		(fp_line
			(start 0.67945 0.3048)
			(end 0.120396 0.3048)
			(stroke
				(width 0.1)
				(type default)
			)
			(layer "F.Fab")
		)
		(fp_line
			(start 0.67945 -0.3048)
			(end 0.67945 0.3048)
			(stroke
				(width 0.1)
				(type default)
			)
			(layer "F.Fab")
		)
		(fp_line
			(start 0.12065 -0.2794)
			(end 0.12065 -0.3048)
			(stroke
				(width 0.1)
				(type default)
			)
			(layer "F.Fab")
		)
		(fp_line
			(start 0.12065 -0.3048)
			(end 0.67945 -0.3048)
			(stroke
				(width 0.1)
				(type default)
			)
			(layer "F.Fab")
		)
		(fp_line
			(start 0.120396 0.3048)
			(end 0.120396 0.2794)
			(stroke
				(width 0.1)
				(type default)
			)
			(layer "F.Fab")
		)
		(fp_line
			(start 0.120396 0.2794)
			(end -0.12065 0.2794)
			(stroke
				(width 0.1)
				(type default)
			)
			(layer "F.Fab")
		)
		(fp_line
			(start -0.12065 0.3048)
			(end -0.67945 0.3048)
			(stroke
				(width 0.1)
				(type default)
			)
			(layer "F.Fab")
		)
		(fp_line
			(start -0.12065 0.2794)
			(end -0.12065 0.3048)
			(stroke
				(width 0.1)
				(type default)
			)
			(layer "F.Fab")
		)
		(fp_line
			(start -0.12065 -0.2794)
			(end 0.12065 -0.2794)
			(stroke
				(width 0.1)
				(type default)
			)
			(layer "F.Fab")
		)
		(fp_line
			(start -0.12065 -0.305054)
			(end -0.12065 -0.2794)
			(stroke
				(width 0.1)
				(type default)
			)
			(layer "F.Fab")
		)
		(fp_line
			(start -0.67945 0.3048)
			(end -0.67945 -0.305054)
			(stroke
				(width 0.1)
				(type default)
			)
			(layer "F.Fab")
		)
		(fp_line
			(start -0.67945 -0.305054)
			(end -0.12065 -0.305054)
			(stroke
				(width 0.1)
				(type default)
			)
			(layer "F.Fab")
		)
		(pad "1" smd circle
			(at -0.40005 0 180)
			(size 0 0)
			(layers "F.Cu" "F.Mask" "F.Paste")
			(net "P5V_AUX")
		)
		(pad "2" smd circle
			(at 0.40005 0 180)
			(size 0 0)
			(layers "F.Cu" "F.Mask" "F.Paste")
			(net "PVDDCR_CPU0_P0_VMON")
		)
	)
	(footprint ""
		(layer "F.Cu")
		(at 22.987254 -35.8013 180)
		(property "Reference" "R1274"
			(at 0 0 180)
			(layer "F.SilkS")
			(hide yes)
			(effects
				(font
					(size 1.27 1.27)
				)
			)
		)
		(property "Value" ""
			(at 0 0 180)
			(layer "F.Fab")
			(effects
				(font
					(size 1.27 1.27)
				)
			)
		)
		(duplicate_pad_numbers_are_jumpers no)
		(fp_line
			(start 0.7874 0.4064)
			(end -0.7874 0.4064)
			(stroke
				(width 0.1524)
				(type default)
			)
			(layer "F.SilkS")
		)
		(fp_line
			(start 0.7874 -0.4064)
			(end 0.7874 0.4064)
			(stroke
				(width 0.1524)
				(type default)
			)
			(layer "F.SilkS")
		)
		(fp_line
			(start -0.7874 0.4064)
			(end -0.7874 -0.4064)
			(stroke
				(width 0.1524)
				(type default)
			)
			(layer "F.SilkS")
		)
		(fp_line
			(start -0.7874 -0.4064)
			(end 0.7874 -0.4064)
			(stroke
				(width 0.1524)
				(type default)
			)
			(layer "F.SilkS")
		)
		(fp_line
			(start 0.67945 0.3048)
			(end 0.120396 0.3048)
			(stroke
				(width 0.1)
				(type default)
			)
			(layer "F.Fab")
		)
		(fp_line
			(start 0.67945 -0.3048)
			(end 0.67945 0.3048)
			(stroke
				(width 0.1)
				(type default)
			)
			(layer "F.Fab")
		)
		(fp_line
			(start 0.12065 -0.2794)
			(end 0.12065 -0.3048)
			(stroke
				(width 0.1)
				(type default)
			)
			(layer "F.Fab")
		)
		(fp_line
			(start 0.12065 -0.3048)
			(end 0.67945 -0.3048)
			(stroke
				(width 0.1)
				(type default)
			)
			(layer "F.Fab")
		)
		(fp_line
			(start 0.120396 0.3048)
			(end 0.120396 0.2794)
			(stroke
				(width 0.1)
				(type default)
			)
			(layer "F.Fab")
		)
		(fp_line
			(start 0.120396 0.2794)
			(end -0.12065 0.2794)
			(stroke
				(width 0.1)
				(type default)
			)
			(layer "F.Fab")
		)
		(fp_line
			(start -0.12065 0.3048)
			(end -0.67945 0.3048)
			(stroke
				(width 0.1)
				(type default)
			)
			(layer "F.Fab")
		)
		(fp_line
			(start -0.12065 0.2794)
			(end -0.12065 0.3048)
			(stroke
				(width 0.1)
				(type default)
			)
			(layer "F.Fab")
		)
		(fp_line
			(start -0.12065 -0.2794)
			(end 0.12065 -0.2794)
			(stroke
				(width 0.1)
				(type default)
			)
			(layer "F.Fab")
		)
		(fp_line
			(start -0.12065 -0.305054)
			(end -0.12065 -0.2794)
			(stroke
				(width 0.1)
				(type default)
			)
			(layer "F.Fab")
		)
		(fp_line
			(start -0.67945 0.3048)
			(end -0.67945 -0.305054)
			(stroke
				(width 0.1)
				(type default)
			)
			(layer "F.Fab")
		)
		(fp_line
			(start -0.67945 -0.305054)
			(end -0.12065 -0.305054)
			(stroke
				(width 0.1)
				(type default)
			)
			(layer "F.Fab")
		)
		(pad "1" smd circle
			(at -0.40005 0 180)
			(size 0 0)
			(layers "F.Cu" "F.Mask" "F.Paste")
			(net "SMB_INA230_7_3V3AUX_SCL_R")
		)
		(pad "2" smd circle
			(at 0.40005 0 180)
			(size 0 0)
			(layers "F.Cu" "F.Mask" "F.Paste")
			(net "SMB_INA230_7_3V3AUX_SCL_R1")
		)
	)
)
